# BASEBOARD_FAB2 (Tioga Pass) — schematic netlist excerpt (pin names and nets, part order shuffled) for the footprints in the layout excerpt that follows; sources: Cadence DE-HDL packaged netlist, KiCad conversion of Wiwynn_Tioga_Pass_MB.brd

CT33  CAP  1000PF 50V 10% X7R  pkg 0402LF  page 224 : A = VR_PVDDQ_GHJ_PH2_SW ; B = VR_PVDDQ_GHJ_PH2_SW_RC
C7G36  CAP_A  0.1UF 16V 10% X7R  pkg 0402V  page 216 : A = VR_FET_SW_P12V_STBY_PVDDQ_ABC ; B = GND
C7F12  CAP  2200PF 50V 10% X7R  pkg 0402LF  page 231 : A = VR_COMP_RC_PVPP_ABC ; B = VR_COMP_PVPP_ABC_3

(kicad_pcb
	(version 20260206)
	(generator "pcbnew")
	(generator_version "10.0")
	(general
		(thickness 1.6)
		(legacy_teardrops no)
	)
	(paper "A4")
	(title_block
		(title "Wiwynn_Tioga_Pass_MB.brd")
		(comment 1 "Tioga Pass / footprints 1765-1767 of 4770")
	)
	(layers
		(0 "F.Cu" signal "TOP")
		(4 "In1.Cu" signal "L2GND")
		(6 "In2.Cu" signal "L3")
		(8 "In3.Cu" signal "L4GND")
		(10 "In4.Cu" signal "L5")
		(12 "In5.Cu" signal "L6GND")
		(14 "In6.Cu" signal "L7VCC")
		(16 "In7.Cu" signal "L8VCC")
		(18 "In8.Cu" signal "L9GND")
		(20 "In9.Cu" signal "L10")
		(22 "In10.Cu" signal "L11GND")
		(24 "In11.Cu" signal "L12")
		(26 "In12.Cu" signal "L13GND")
		(2 "B.Cu" signal "BOTTOM")
		(9 "F.Adhes" user "F.Adhesive")
		(11 "B.Adhes" user "B.Adhesive")
		(13 "F.Paste" user "Package Geometry/Pastemask Top")
		(15 "B.Paste" user "Package Geometry/Pastemask Bottom")
		(5 "F.SilkS" user "Ref Des/Silkscreen Top")
		(7 "B.SilkS" user "Ref Des/Silkscreen Bottom")
		(1 "F.Mask" user "Board Geometry/Soldermask Top")
		(3 "B.Mask" user "Board Geometry/Soldermask Bottom")
		(17 "Dwgs.User" user "User.Drawings")
		(19 "Cmts.User" user "User.Comments")
		(21 "Eco1.User" user "User.Eco1")
		(23 "Eco2.User" user "User.Eco2")
		(25 "Edge.Cuts" user "Board Geometry/Outline")
		(27 "Margin" user)
		(31 "F.CrtYd" user "Package Geometry/Place Bound Top")
		(29 "B.CrtYd" user "Package Geometry/Place Bound Bottom")
		(35 "F.Fab" user "Ref Des/Assembly Top")
		(33 "B.Fab" user "Ref Des/Assembly Bottom")
	)
	(footprint ""
		(layer "F.Cu")
		(at 343.789 -22.64156 90)
		(property "Reference" "C7F12"
			(at 0 0 90)
			(layer "F.SilkS")
			(hide yes)
			(effects
				(font
					(size 1.27 1.27)
				)
			)
		)
		(property "Value" ""
			(at 0 0 90)
			(layer "F.Fab")
			(effects
				(font
					(size 1.27 1.27)
				)
			)
		)
		(duplicate_pad_numbers_are_jumpers no)
		(fp_poly
			(pts
				(xy 0.3048 -0.1016) (xy 0.3048 0.9906) (xy -0.3048 0.9906) (xy -0.3048 -0.1016)
			)
			(stroke
				(width 0)
				(type default)
			)
			(fill no)
			(layer "F.CrtYd")
		)
		(fp_line
			(start 0.3048 -0.1016)
			(end -0.3048 -0.1016)
			(stroke
				(width 0.1)
				(type default)
			)
			(layer "F.Fab")
		)
		(fp_line
			(start -0.3048 -0.1016)
			(end -0.3048 0.9906)
			(stroke
				(width 0.1)
				(type default)
			)
			(layer "F.Fab")
		)
		(fp_line
			(start 0.3048 0.9906)
			(end 0.3048 -0.1016)
			(stroke
				(width 0.1)
				(type default)
			)
			(layer "F.Fab")
		)
		(fp_line
			(start -0.3048 0.9906)
			(end 0.3048 0.9906)
			(stroke
				(width 0.1)
				(type default)
			)
			(layer "F.Fab")
		)
		(pad "1" smd rect
			(at 0 0 90)
			(size 0.508 0.508)
			(layers "F.Cu" "F.Mask" "F.Paste")
			(net "VR_COMP_RC_PVPP_ABC")
		)
		(pad "2" smd rect
			(at 0 0.889 90)
			(size 0.508 0.508)
			(layers "F.Cu" "F.Mask" "F.Paste")
			(net "VR_COMP_PVPP_ABC_3")
		)
		(zone
			(layer "F.Cu")
			(hatch none 0.5)
			(connect_pads
				(clearance 0)
			)
			(min_thickness 0.25)
			(keepout
				(tracks allowed)
				(vias not_allowed)
				(pads allowed)
				(copperpour not_allowed)
				(footprints allowed)
			)
			(placement
				(enabled no)
				(sheetname "")
			)
			(fill
				(thermal_gap 0.5)
				(thermal_bridge_width 0.5)
				(island_removal_mode 0)
			)
			(polygon
				(pts
					(xy 344.043 -22.38756) (xy 344.043 -22.89556) (xy 344.424 -22.89556) (xy 344.424 -22.38756)
				)
			)
		)
		(zone
			(layer "F.Cu")
			(hatch none 0.5)
			(connect_pads
				(clearance 0)
			)
			(min_thickness 0.25)
			(keepout
				(tracks not_allowed)
				(vias allowed)
				(pads allowed)
				(copperpour not_allowed)
				(footprints allowed)
			)
			(placement
				(enabled no)
				(sheetname "")
			)
			(fill
				(thermal_gap 0.5)
				(thermal_bridge_width 0.5)
				(island_removal_mode 0)
			)
			(polygon
				(pts
					(xy 344.424 -22.38756) (xy 344.424 -22.89556) (xy 344.043 -22.89556) (xy 344.043 -22.38756)
				)
			)
		)
	)
	(footprint ""
		(layer "F.Cu")
		(at 346.906342 5.168646 -90)
		(property "Reference" "C7G36"
			(at 0 0 270)
			(layer "F.SilkS")
			(hide yes)
			(effects
				(font
					(size 1.27 1.27)
				)
			)
		)
		(property "Value" ""
			(at 0 0 270)
			(layer "F.Fab")
			(effects
				(font
					(size 1.27 1.27)
				)
			)
		)
		(duplicate_pad_numbers_are_jumpers no)
		(fp_rect
			(start -0.3048 0.9906)
			(end 0.3048 -0.1016)
			(stroke
				(width 0)
				(type default)
			)
			(fill no)
			(layer "F.CrtYd")
		)
		(fp_line
			(start -0.3048 0.9906)
			(end 0.3048 0.9906)
			(stroke
				(width 0.1)
				(type default)
			)
			(layer "F.Fab")
		)
		(fp_line
			(start 0.3048 0.9906)
			(end 0.3048 -0.1016)
			(stroke
				(width 0.1)
				(type default)
			)
			(layer "F.Fab")
		)
		(fp_line
			(start -0.3048 -0.1016)
			(end -0.3048 0.9906)
			(stroke
				(width 0.1)
				(type default)
			)
			(layer "F.Fab")
		)
		(fp_line
			(start 0.3048 -0.1016)
			(end -0.3048 -0.1016)
			(stroke
				(width 0.1)
				(type default)
			)
			(layer "F.Fab")
		)
		(pad "1" smd rect
			(at 0 0 270)
			(size 0.508 0.508)
			(layers "F.Cu" "F.Mask" "F.Paste")
			(net "VR_FET_SW_P12V_STBY_PVDDQ_ABC")
		)
		(pad "2" smd rect
			(at 0 0.889 270)
			(size 0.508 0.508)
			(layers "F.Cu" "F.Mask" "F.Paste")
			(net "GND")
		)
		(zone
			(layer "F.Cu")
			(hatch none 0.5)
			(connect_pads
				(clearance 0)
			)
			(min_thickness 0.25)
			(keepout
				(tracks not_allowed)
				(vias allowed)
				(pads allowed)
				(copperpour not_allowed)
				(footprints allowed)
			)
			(placement
				(enabled no)
				(sheetname "")
			)
			(fill
				(thermal_gap 0.5)
				(thermal_bridge_width 0.5)
				(island_removal_mode 0)
			)
			(polygon
				(pts
					(xy 346.271342 4.914646) (xy 346.271342 5.422646) (xy 346.652342 5.422646) (xy 346.652342 4.914646)
				)
			)
		)
		(zone
			(layer "F.Cu")
			(hatch none 0.5)
			(connect_pads
				(clearance 0)
			)
			(min_thickness 0.25)
			(keepout
				(tracks allowed)
				(vias not_allowed)
				(pads allowed)
				(copperpour not_allowed)
				(footprints allowed)
			)
			(placement
				(enabled no)
				(sheetname "")
			)
			(fill
				(thermal_gap 0.5)
				(thermal_bridge_width 0.5)
				(island_removal_mode 0)
			)
			(polygon
				(pts
					(xy 346.271342 4.914646) (xy 346.271342 5.422646) (xy 346.652342 5.422646) (xy 346.652342 4.914646)
				)
			)
		)
	)
	(footprint ""
		(layer "F.Cu")
		(at 8.763 -13.843)
		(property "Reference" "CT33"
			(at -0.8382 -0.67818 0)
			(unlocked yes)
			(layer "F.SilkS")
			(effects
				(font
					(size 0.4064 0.254)
					(thickness 0.1524)
				)
				(justify left)
			)
		)
		(property "Value" ""
			(at 0 0 0)
			(layer "F.Fab")
			(effects
				(font
					(size 1.27 1.27)
				)
			)
		)
		(duplicate_pad_numbers_are_jumpers no)
		(fp_poly
			(pts
				(xy 0.3048 -0.1016) (xy 0.3048 0.9906) (xy -0.3048 0.9906) (xy -0.3048 -0.1016)
			)
			(stroke
				(width 0)
				(type default)
			)
			(fill no)
			(layer "F.CrtYd")
		)
		(fp_line
			(start -0.3048 -0.1016)
			(end -0.3048 0.9906)
			(stroke
				(width 0.1)
				(type default)
			)
			(layer "F.Fab")
		)
		(fp_line
			(start -0.3048 0.9906)
			(end 0.3048 0.9906)
			(stroke
				(width 0.1)
				(type default)
			)
			(layer "F.Fab")
		)
		(fp_line
			(start 0.3048 -0.1016)
			(end -0.3048 -0.1016)
			(stroke
				(width 0.1)
				(type default)
			)
			(layer "F.Fab")
		)
		(fp_line
			(start 0.3048 0.9906)
			(end 0.3048 -0.1016)
			(stroke
				(width 0.1)
				(type default)
			)
			(layer "F.Fab")
		)
		(pad "1" smd rect
			(at 0 0)
			(size 0.508 0.508)
			(layers "F.Cu" "F.Mask" "F.Paste")
			(net "VR_PVDDQ_GHJ_PH2_SW")
		)
		(pad "2" smd rect
			(at 0 0.889)
			(size 0.508 0.508)
			(layers "F.Cu" "F.Mask" "F.Paste")
			(net "VR_PVDDQ_GHJ_PH2_SW_RC")
		)
		(zone
			(layer "F.Cu")
			(hatch none 0.5)
			(connect_pads
				(clearance 0)
			)
			(min_thickness 0.25)
			(keepout
				(tracks allowed)
				(vias not_allowed)
				(pads allowed)
				(copperpour not_allowed)
				(footprints allowed)
			)
			(placement
				(enabled no)
				(sheetname "")
			)
			(fill
				(thermal_gap 0.5)
				(thermal_bridge_width 0.5)
				(island_removal_mode 0)
			)
			(polygon
				(pts
					(xy 8.509 -13.589) (xy 9.017 -13.589) (xy 9.017 -13.208) (xy 8.509 -13.208)
				)
			)
		)
		(zone
			(layer "F.Cu")
			(hatch none 0.5)
			(connect_pads
				(clearance 0)
			)
			(min_thickness 0.25)
			(keepout
				(tracks not_allowed)
				(vias allowed)
				(pads allowed)
				(copperpour not_allowed)
				(footprints allowed)
			)
			(placement
				(enabled no)
				(sheetname "")
			)
			(fill
				(thermal_gap 0.5)
				(thermal_bridge_width 0.5)
				(island_removal_mode 0)
			)
			(polygon
				(pts
					(xy 8.509 -13.208) (xy 9.017 -13.208) (xy 9.017 -13.589) (xy 8.509 -13.589)
				)
			)
		)
	)
)
